(kicad_pcb
	(version 20221018)
	(generator pcbnew)
	(general
    (thickness 1.6)
  )
	(paper "A4")
	(title_block
    (title "NUC Computer Cluster Power Breakout HW")
    (date "2023-10-18")
    (rev "1.4.3")
    (company "Antmicro Ltd.")
		(comment 9 "footprints 69-77 of 234")
	)
	(layers
    (0 "F.Cu" mixed)
    (1 "In1.Cu" power)
    (2 "In2.Cu" mixed)
    (31 "B.Cu" power)
    (32 "B.Adhes" user "B.Adhesive")
    (33 "F.Adhes" user "F.Adhesive")
    (34 "B.Paste" user)
    (35 "F.Paste" user)
    (36 "B.SilkS" user "B.Silkscreen")
    (37 "F.SilkS" user "F.Silkscreen")
    (38 "B.Mask" user)
    (39 "F.Mask" user)
    (40 "Dwgs.User" user "User.Drawings")
    (41 "Cmts.User" user "User.Comments")
    (42 "Eco1.User" user "User.Eco1")
    (43 "Eco2.User" user "User.Eco2")
    (44 "Edge.Cuts" user)
    (45 "Margin" user)
    (46 "B.CrtYd" user "B.Courtyard")
    (47 "F.CrtYd" user "F.Courtyard")
    (48 "B.Fab" user)
    (49 "F.Fab" user)
  )
	(footprint "antmicro-footprints:TP_SMD_1mm" (layer "F.Cu")
    (at 159.8 91.45)
    (property "Author" "Antmicro")
    (property "License" "Apache-2.0")
    (property "MPN" "")
    (property "Manufacturer" "")
    (property "Sheetfile" "pow-cycl-curr-meas.kicad_sch")
    (property "Sheetname" "Power Cycling & Current Measurement")
    (property "exclude_from_bom" "")
    (property "ki_description" "Test point 1mm SMD")
    (property "ki_keywords" "TESTPOINT")
    (attr exclude_from_pos_files exclude_from_bom)
    (fp_text reference "TP_PC3" (at -2.65 -0.0008) (layer "F.SilkS") hide
        (effects (font (size 0.7 0.7) (thickness 0.15)))
    )
    (fp_text value "TP_1mm_SMD" (at 0 -0.5) (layer "F.Fab") hide
        (effects (font (size 1 1) (thickness 0.15)))
    )
    (fp_text user "Author: Antmicro" (at -0.5 4) (layer "F.Fab") hide
        (effects (font (size 0.7 0.7) (thickness 0.15)) (justify left bottom))
    )
    (fp_text user "License: Apache-2.0" (at -0.5 5.2) (layer "F.Fab") hide
        (effects (font (size 0.7 0.7) (thickness 0.15)) (justify left bottom))
    )
    (fp_text user "${REFERENCE}" (at -0.5 2.8) (layer "F.Fab") hide
        (effects (font (size 0.7 0.7) (thickness 0.15)) (justify left bottom))
    )
    (fp_circle (center 0 0) (end 0.6 0)
      (stroke (width 0.05) (type default)) (fill none) (layer "F.CrtYd"))
    (pad "1" smd circle (at 0 0) (size 1 1) (layers "F.Cu" "F.Mask")
      (net 30 "/Power Cycling & Current Measurement/PC_3") (pinfunction "1") (pintype "passive"))
  )
	(footprint "antmicro-footprints:TP_SMD_1mm" (layer "F.Cu")
    (at 160.87 93.57)
    (property "Author" "Antmicro")
    (property "License" "Apache-2.0")
    (property "MPN" "")
    (property "Manufacturer" "")
    (property "Sheetfile" "pow-cycl-curr-meas.kicad_sch")
    (property "Sheetname" "Power Cycling & Current Measurement")
    (property "exclude_from_bom" "")
    (property "ki_description" "Test point 1mm SMD")
    (property "ki_keywords" "TESTPOINT")
    (attr exclude_from_pos_files exclude_from_bom)
    (fp_text reference "TP_PC4" (at -1.4 -1.2) (layer "F.SilkS") hide
        (effects (font (size 0.7 0.7) (thickness 0.15)))
    )
    (fp_text value "TP_1mm_SMD" (at 0 -0.5) (layer "F.Fab") hide
        (effects (font (size 1 1) (thickness 0.15)))
    )
    (fp_text user "${REFERENCE}" (at -0.5 2.8) (layer "F.Fab") hide
        (effects (font (size 0.7 0.7) (thickness 0.15)) (justify left bottom))
    )
    (fp_text user "Author: Antmicro" (at -0.5 4) (layer "F.Fab") hide
        (effects (font (size 0.7 0.7) (thickness 0.15)) (justify left bottom))
    )
    (fp_text user "License: Apache-2.0" (at -0.5 5.2) (layer "F.Fab") hide
        (effects (font (size 0.7 0.7) (thickness 0.15)) (justify left bottom))
    )
    (fp_circle (center 0 0) (end 0.6 0)
      (stroke (width 0.05) (type default)) (fill none) (layer "F.CrtYd"))
    (pad "1" smd circle (at 0 0) (size 1 1) (layers "F.Cu" "F.Mask")
      (net 29 "/Power Cycling & Current Measurement/PC_4") (pinfunction "1") (pintype "passive"))
  )
	(footprint "antmicro-footprints:TP_SMD_1mm" (layer "F.Cu")
    (at 161.4 92.3508)
    (property "Author" "Antmicro")
    (property "License" "Apache-2.0")
    (property "MPN" "")
    (property "Manufacturer" "")
    (property "Sheetfile" "pow-cycl-curr-meas.kicad_sch")
    (property "Sheetname" "Power Cycling & Current Measurement")
    (property "exclude_from_bom" "")
    (property "ki_description" "Test point 1mm SMD")
    (property "ki_keywords" "TESTPOINT")
    (attr exclude_from_pos_files exclude_from_bom)
    (fp_text reference "TP_PC5" (at 2.6 0.05) (layer "F.SilkS") hide
        (effects (font (size 0.7 0.7) (thickness 0.15)))
    )
    (fp_text value "TP_1mm_SMD" (at 0 -0.5) (layer "F.Fab") hide
        (effects (font (size 1 1) (thickness 0.15)))
    )
    (fp_text user "License: Apache-2.0" (at -0.5 5.2) (layer "F.Fab") hide
        (effects (font (size 0.7 0.7) (thickness 0.15)) (justify left bottom))
    )
    (fp_text user "${REFERENCE}" (at -0.5 2.8) (layer "F.Fab") hide
        (effects (font (size 0.7 0.7) (thickness 0.15)) (justify left bottom))
    )
    (fp_text user "Author: Antmicro" (at -0.5 4) (layer "F.Fab") hide
        (effects (font (size 0.7 0.7) (thickness 0.15)) (justify left bottom))
    )
    (fp_circle (center 0 0) (end 0.6 0)
      (stroke (width 0.05) (type default)) (fill none) (layer "F.CrtYd"))
    (pad "1" smd circle (at 0 0) (size 1 1) (layers "F.Cu" "F.Mask")
      (net 26 "/Power Cycling & Current Measurement/PC_5") (pinfunction "1") (pintype "passive"))
  )
	(footprint "antmicro-footprints:TP_SMD_1mm" (layer "F.Cu")
    (at 108.85 82.0508)
    (property "Author" "Antmicro")
    (property "License" "Apache-2.0")
    (property "MPN" "")
    (property "Manufacturer" "")
    (property "Sheetfile" "pow-cycl-curr-meas.kicad_sch")
    (property "Sheetname" "Power Cycling & Current Measurement")
    (property "exclude_from_bom" "")
    (property "ki_description" "Test point 1mm SMD")
    (property "ki_keywords" "TESTPOINT")
    (attr exclude_from_pos_files exclude_from_bom)
    (fp_text reference "TP_ADC1" (at 0 -0.731898) (layer "F.SilkS") hide
        (effects (font (size 0.7 0.7) (thickness 0.15)) (justify left bottom))
    )
    (fp_text value "TP_1mm_SMD" (at 0 1.4) (layer "F.Fab")
        (effects (font (size 0.7 0.7) (thickness 0.15)) (justify left bottom))
    )
    (fp_text user "Author: Antmicro" (at -0.5 4) (layer "F.Fab") hide
        (effects (font (size 0.7 0.7) (thickness 0.15)) (justify left bottom))
    )
    (fp_text user "${REFERENCE}" (at -0.5 2.8) (layer "F.Fab") hide
        (effects (font (size 0.7 0.7) (thickness 0.15)) (justify left bottom))
    )
    (fp_text user "License: Apache-2.0" (at -0.5 5.2) (layer "F.Fab") hide
        (effects (font (size 0.7 0.7) (thickness 0.15)) (justify left bottom))
    )
    (fp_circle (center 0 0) (end 0.6 0)
      (stroke (width 0.05) (type default)) (fill none) (layer "F.CrtYd"))
    (pad "1" smd circle (at 0 0) (size 1 1) (layers "F.Cu" "F.Mask")
      (net 46 "/Power Cycling & Current Measurement/C_ADC1") (pinfunction "1") (pintype "passive"))
  )
	(footprint "antmicro-footprints:TP_SMD_1mm" (layer "F.Cu")
    (at 158.55 93.0508)
    (property "Author" "Antmicro")
    (property "License" "Apache-2.0")
    (property "MPN" "")
    (property "Manufacturer" "")
    (property "Sheetfile" "pow-cycl-curr-meas.kicad_sch")
    (property "Sheetname" "Power Cycling & Current Measurement")
    (property "exclude_from_bom" "")
    (property "ki_description" "Test point 1mm SMD")
    (property "ki_keywords" "TESTPOINT")
    (attr exclude_from_pos_files exclude_from_bom)
    (fp_text reference "TP_PC2" (at -2.5 0.3992) (layer "F.SilkS") hide
        (effects (font (size 0.7 0.7) (thickness 0.15)))
    )
    (fp_text value "TP_1mm_SMD" (at 0 -0.5) (layer "F.Fab") hide
        (effects (font (size 1 1) (thickness 0.15)))
    )
    (fp_text user "License: Apache-2.0" (at -0.5 5.2) (layer "F.Fab") hide
        (effects (font (size 0.7 0.7) (thickness 0.15)) (justify left bottom))
    )
    (fp_text user "Author: Antmicro" (at -0.5 4) (layer "F.Fab") hide
        (effects (font (size 0.7 0.7) (thickness 0.15)) (justify left bottom))
    )
    (fp_text user "${REFERENCE}" (at -0.5 2.8) (layer "F.Fab") hide
        (effects (font (size 0.7 0.7) (thickness 0.15)) (justify left bottom))
    )
    (fp_circle (center 0 0) (end 0.6 0)
      (stroke (width 0.05) (type default)) (fill none) (layer "F.CrtYd"))
    (pad "1" smd circle (at 0 0) (size 1 1) (layers "F.Cu" "F.Mask")
      (net 24 "/Power Cycling & Current Measurement/PC_2") (pinfunction "1") (pintype "passive"))
  )
	(footprint "antmicro-footprints:TP_SMD_1mm" (layer "F.Cu")
    (at 157.2 94.3008)
    (property "Author" "Antmicro")
    (property "License" "Apache-2.0")
    (property "MPN" "")
    (property "Manufacturer" "")
    (property "Sheetfile" "pow-cycl-curr-meas.kicad_sch")
    (property "Sheetname" "Power Cycling & Current Measurement")
    (property "exclude_from_bom" "")
    (property "ki_description" "Test point 1mm SMD")
    (property "ki_keywords" "TESTPOINT")
    (attr exclude_from_pos_files exclude_from_bom)
    (fp_text reference "TP_PC1" (at 2.45 -0.0508) (layer "F.SilkS") hide
        (effects (font (size 0.7 0.7) (thickness 0.15)))
    )
    (fp_text value "TP_1mm_SMD" (at 0 -0.5) (layer "F.Fab") hide
        (effects (font (size 1 1) (thickness 0.15)))
    )
    (fp_text user "${REFERENCE}" (at -0.5 2.8) (layer "F.Fab") hide
        (effects (font (size 0.7 0.7) (thickness 0.15)) (justify left bottom))
    )
    (fp_text user "Author: Antmicro" (at -0.5 4) (layer "F.Fab") hide
        (effects (font (size 0.7 0.7) (thickness 0.15)) (justify left bottom))
    )
    (fp_text user "License: Apache-2.0" (at -0.5 5.2) (layer "F.Fab") hide
        (effects (font (size 0.7 0.7) (thickness 0.15)) (justify left bottom))
    )
    (fp_circle (center 0 0) (end 0.6 0)
      (stroke (width 0.05) (type default)) (fill none) (layer "F.CrtYd"))
    (pad "1" smd circle (at 0 0) (size 1 1) (layers "F.Cu" "F.Mask")
      (net 23 "/Power Cycling & Current Measurement/PC_1") (pinfunction "1") (pintype "passive"))
  )
	(footprint "antmicro-footprints:R_0402_1005Metric" (layer "F.Cu")
    (at 103.8 136 -90)
    (descr "Resistor SMD 0402")
    (tags "resistor SMD 0402")
    (property "Author" "Antmicro")
    (property "License" "Apache-2.0")
    (property "MPN" "CR0402-FX-1002GLF")
    (property "Manufacturer" "Bourns")
    (property "Sheetfile" "d1600e-psu-breakout-board.kicad_sch")
    (property "Sheetname" "")
    (property "Tolerance" "1%")
    (property "Val" "10k")
    (property "ki_description" "SMD Chip Resistor, 10 kohm, ± 1%, 62.5 mW, 0402 [1005 Metric], Thick Film, General Purpose")
    (property "ki_keywords" "0402, SMT, RESISTOR, PASSIVE")
    (attr smd)
    (fp_text reference "R40" (at 1.1 -1.6 -90) (layer "F.SilkS")
        (effects (font (size 0.7 0.7) (thickness 0.15)) (justify left bottom))
    )
    (fp_text value "R_10k_0402" (at -1.011843 1.772047 -90) (layer "F.Fab")
        (effects (font (size 0.7 0.7) (thickness 0.15)) (justify left bottom))
    )
    (fp_text user "Author: Antmicro" (at -0.95 4.169 -90) (layer "F.Fab") hide
        (effects (font (size 0.7 0.7) (thickness 0.15)) (justify left bottom))
    )
    (fp_text user "${REFERENCE}" (at -0.95 3.168 -90) (layer "F.Fab") hide
        (effects (font (size 0.7 0.7) (thickness 0.15)) (justify left bottom))
    )
    (fp_text user "License: Apache-2.0" (at -0.95 5.169 -90) (layer "F.Fab") hide
        (effects (font (size 0.7 0.7) (thickness 0.15)) (justify left bottom))
    )
    (fp_rect (start -0.925 -0.47) (end 0.925 0.47)
      (stroke (width 0.05) (type default)) (fill none) (layer "F.CrtYd"))
    (fp_rect (start -0.5 -0.25) (end 0.5 0.25)
      (stroke (width 0.15) (type solid)) (fill none) (layer "F.Fab"))
    (pad "1" smd roundrect (at -0.48 0 270) (size 0.59 0.64) (layers "F.Cu" "F.Paste" "F.Mask") (roundrect_rratio 0.25)
      (net 54 "Net-(Q11-Pad1)") (pintype "passive"))
    (pad "2" smd roundrect (at 0.48 0 270) (size 0.59 0.64) (layers "F.Cu" "F.Paste" "F.Mask") (roundrect_rratio 0.25)
      (net 51 "PSU_ON") (pintype "passive"))
  )
	(footprint "antmicro-footprints:LED_0603_1608Metric_G" (layer "F.Cu")
    (at 98 133.8 -90)
    (descr "LED SMD 0603 Green")
    (tags "LED SMD 0603 Green")
    (property "Author" "Antmicro")
    (property "Color" "Green")
    (property "License" "Apache-2.0")
    (property "MPN" "LG L29K-G2J1-24-Z")
    (property "Manufacturer" "OSRAM")
    (property "Sheetfile" "d1600e-psu-breakout-board.kicad_sch")
    (property "Sheetname" "")
    (property "ki_description" "LED, Green, SMD, 0603, 20 mA, 1.7 V, 570 nm")
    (property "ki_keywords" "SMT, DIODE, SEMICONDUCTOR, LED")
    (attr smd)
    (fp_text reference "D5" (at -1.65 -0.45 -90) (layer "F.SilkS")
        (effects (font (size 0.7 0.7) (thickness 0.15)) (justify left bottom))
    )
    (fp_text value "LED_G_0603_LG_L29K-G2J1-24-Z" (at -0.001 1.599 -90) (layer "F.Fab")
        (effects (font (size 0.7 0.7) (thickness 0.15)) (justify left bottom))
    )
    (fp_text user "${REFERENCE}" (at -1.4224 5.999 -90) (layer "F.Fab") hide
        (effects (font (size 0.7 0.7) (thickness 0.15)) (justify left bottom))
    )
    (fp_text user "License: Apache-2.0" (at -1.4224 3.599 -90) (layer "F.Fab") hide
        (effects (font (size 0.7 0.7) (thickness 0.15)) (justify left bottom))
    )
    (fp_text user "Author: Antmicro" (at -1.4224 4.799 -90) (layer "F.Fab") hide
        (effects (font (size 0.7 0.7) (thickness 0.15)) (justify left bottom))
    )
    (fp_line (start -1.18 -0.319) (end -1.18 0.321)
      (stroke (width 0.15) (type solid)) (layer "F.SilkS"))
    (fp_line (start -0.094672 0.001008) (end -0.24 0.001008)
      (stroke (width 0.1) (type solid)) (layer "F.SilkS"))
    (fp_line (start -0.094672 0.001008) (end 0.105328 -0.198992)
      (stroke (width 0.1) (type solid)) (layer "F.SilkS"))
    (fp_line (start -0.094672 0.201008) (end -0.094672 -0.198992)
      (stroke (width 0.1) (type solid)) (layer "F.SilkS"))
    (fp_line (start 0.105328 0.001008) (end 0.24 0.001)
      (stroke (width 0.1) (type solid)) (layer "F.SilkS"))
    (fp_line (start 0.105328 0.201008) (end -0.094672 0.001008)
      (stroke (width 0.1) (type solid)) (layer "F.SilkS"))
    (fp_line (start 0.105328 0.201008) (end 0.105328 -0.198992)
      (stroke (width 0.1) (type solid)) (layer "F.SilkS"))
    (fp_line (start 0.22 -0.35) (end -0.22 -0.35)
      (stroke (width 0.15) (type solid)) (layer "F.SilkS"))
    (fp_line (start 0.22 0.35) (end -0.22 0.35)
      (stroke (width 0.15) (type solid)) (layer "F.SilkS"))
    (fp_rect (start 1.25 0.65) (end -1.25 -0.65)
      (stroke (width 0.05) (type solid)) (fill none) (layer "F.CrtYd"))
    (fp_line (start -0.199 -0.202) (end -0.199 0.1)
      (stroke (width 0.15) (type solid)) (layer "F.Fab"))
    (fp_line (start -0.199 0) (end -0.597 0)
      (stroke (width 0.15) (type solid)) (layer "F.Fab"))
    (fp_line (start -0.199 0.2) (end -0.199 0.1)
      (stroke (width 0.15) (type solid)) (layer "F.Fab"))
    (fp_line (start -0.101 0) (end 0.201 0.2)
      (stroke (width 0.15) (type solid)) (layer "F.Fab"))
    (fp_line (start 0.201 -0.202) (end -0.101 0)
      (stroke (width 0.15) (type solid)) (layer "F.Fab"))
    (fp_line (start 0.201 0) (end 0.201 -0.202)
      (stroke (width 0.15) (type solid)) (layer "F.Fab"))
    (fp_line (start 0.201 0.2) (end 0.201 0)
      (stroke (width 0.15) (type solid)) (layer "F.Fab"))
    (fp_line (start 0.599 0) (end 0.201 0)
      (stroke (width 0.15) (type solid)) (layer "F.Fab"))
    (fp_rect (start 0.848 0.4) (end -0.85 -0.402)
      (stroke (width 0.15) (type solid)) (fill none) (layer "F.Fab"))
    (pad "1" smd roundrect (at -0.7 0 90) (size 0.8 1) (layers "F.Cu" "F.Paste" "F.Mask") (roundrect_rratio 0.2)
      (net 38 "Net-(D5-C)") (pinfunction "C") (pintype "passive"))
    (pad "2" smd roundrect (at 0.7 0 90) (size 0.8 1) (layers "F.Cu" "F.Paste" "F.Mask") (roundrect_rratio 0.2)
      (net 39 "Net-(D5-A)") (pinfunction "A") (pintype "passive"))
  )
	(footprint "antmicro-footprints:R_0402_1005Metric" (layer "F.Cu")
    (at 96.4 133.8 -90)
    (descr "Resistor SMD 0402")
    (tags "resistor SMD 0402")
    (property "Author" "Antmicro")
    (property "License" "Apache-2.0")
    (property "MPN" "CR0402-FX-6800GLF")
    (property "Manufacturer" "Bourns")
    (property "Sheetfile" "d1600e-psu-breakout-board.kicad_sch")
    (property "Sheetname" "")
    (property "Tolerance" "1%")
    (property "Val" "680R")
    (property "ki_description" "SMD Chip Resistor, 680 ohm, ± 1%, 63 mW, 0402 [1005 Metric], Thick Film, General Purpose")
    (property "ki_keywords" "0402, SMT, RESISTOR, PASSIVE")
    (attr smd)
    (fp_text reference "R41" (at -0.9 -0.4 -90) (layer "F.SilkS")
        (effects (font (size 0.7 0.7) (thickness 0.15)) (justify left bottom))
    )
    (fp_text value "R_680R_0402" (at -1.011843 1.772047 -90) (layer "F.Fab")
        (effects (font (size 0.7 0.7) (thickness 0.15)) (justify left bottom))
    )
    (fp_text user "License: Apache-2.0" (at -0.95 5.169 -90) (layer "F.Fab") hide
        (effects (font (size 0.7 0.7) (thickness 0.15)) (justify left bottom))
    )
    (fp_text user "Author: Antmicro" (at -0.95 4.169 -90) (layer "F.Fab") hide
        (effects (font (size 0.7 0.7) (thickness 0.15)) (justify left bottom))
    )
    (fp_text user "${REFERENCE}" (at -0.95 3.168 -90) (layer "F.Fab") hide
        (effects (font (size 0.7 0.7) (thickness 0.15)) (justify left bottom))
    )
    (fp_rect (start -0.925 -0.47) (end 0.925 0.47)
      (stroke (width 0.05) (type default)) (fill none) (layer "F.CrtYd"))
    (fp_rect (start -0.5 -0.25) (end 0.5 0.25)
      (stroke (width 0.15) (type solid)) (fill none) (layer "F.Fab"))
    (pad "1" smd roundrect (at -0.48 0 270) (size 0.59 0.64) (layers "F.Cu" "F.Paste" "F.Mask") (roundrect_rratio 0.25)
      (net 38 "Net-(D5-C)") (pintype "passive"))
    (pad "2" smd roundrect (at 0.48 0 270) (size 0.59 0.64) (layers "F.Cu" "F.Paste" "F.Mask") (roundrect_rratio 0.25)
      (net 4 "GND") (pintype "passive"))
  )
)
